# BASEBOARD_FAB2 (Tioga Pass) — schematic netlist excerpt (pin names and nets, part order shuffled) for the footprints in the layout excerpt that follows; sources: Cadence DE-HDL packaged netlist, KiCad conversion of Wiwynn_Tioga_Pass_MB.brd

C5D53  CAP_A  22.0UF 4V 20% X6S  pkg 0603V  page 42 : A = PVCCMCP_CPU0 ; B = GND
R8B16  RES  4.75K 1% CHIP  pkg 0402  page 91 : A = PVPP_ABC ; B = RST_HFI1_CPU0_LVT2_N

(kicad_pcb
	(version 20260206)
	(generator "pcbnew")
	(generator_version "10.0")
	(general
		(thickness 1.6)
		(legacy_teardrops no)
	)
	(paper "A4")
	(title_block
		(title "Wiwynn_Tioga_Pass_MB.brd")
		(comment 1 "Tioga Pass / footprints 1439-1440 of 4770")
	)
	(layers
		(0 "F.Cu" signal "TOP")
		(4 "In1.Cu" signal "L2GND")
		(6 "In2.Cu" signal "L3")
		(8 "In3.Cu" signal "L4GND")
		(10 "In4.Cu" signal "L5")
		(12 "In5.Cu" signal "L6GND")
		(14 "In6.Cu" signal "L7VCC")
		(16 "In7.Cu" signal "L8VCC")
		(18 "In8.Cu" signal "L9GND")
		(20 "In9.Cu" signal "L10")
		(22 "In10.Cu" signal "L11GND")
		(24 "In11.Cu" signal "L12")
		(26 "In12.Cu" signal "L13GND")
		(2 "B.Cu" signal "BOTTOM")
		(9 "F.Adhes" user "F.Adhesive")
		(11 "B.Adhes" user "B.Adhesive")
		(13 "F.Paste" user "Package Geometry/Pastemask Top")
		(15 "B.Paste" user "Package Geometry/Pastemask Bottom")
		(5 "F.SilkS" user "Ref Des/Silkscreen Top")
		(7 "B.SilkS" user "Ref Des/Silkscreen Bottom")
		(1 "F.Mask" user "Board Geometry/Soldermask Top")
		(3 "B.Mask" user "Board Geometry/Soldermask Bottom")
		(17 "Dwgs.User" user "User.Drawings")
		(19 "Cmts.User" user "User.Comments")
		(21 "Eco1.User" user "User.Eco1")
		(23 "Eco2.User" user "User.Eco2")
		(25 "Edge.Cuts" user "Board Geometry/Outline")
		(27 "Margin" user)
		(31 "F.CrtYd" user "Package Geometry/Place Bound Top")
		(29 "B.CrtYd" user "Package Geometry/Place Bound Bottom")
		(35 "F.Fab" user "Ref Des/Assembly Top")
		(33 "B.Fab" user "Ref Des/Assembly Bottom")
	)
	(footprint ""
		(layer "F.Cu")
		(at 426.4533 -124.9172 -90)
		(property "Reference" "R8B16"
			(at 0 0 270)
			(layer "F.SilkS")
			(hide yes)
			(effects
				(font
					(size 1.27 1.27)
				)
			)
		)
		(property "Value" ""
			(at 0 0 270)
			(layer "F.Fab")
			(effects
				(font
					(size 1.27 1.27)
				)
			)
		)
		(duplicate_pad_numbers_are_jumpers no)
		(fp_poly
			(pts
				(xy -0.2794 -0.1016) (xy 0.2794 -0.1016) (xy 0.2794 0.9906) (xy -0.2794 0.9906)
			)
			(stroke
				(width 0)
				(type default)
			)
			(fill no)
			(layer "F.CrtYd")
		)
		(fp_line
			(start -0.2794 0.9906)
			(end 0.2794 0.9906)
			(stroke
				(width 0.1)
				(type default)
			)
			(layer "F.Fab")
		)
		(fp_line
			(start 0.2794 0.9906)
			(end 0.2794 -0.1016)
			(stroke
				(width 0.1)
				(type default)
			)
			(layer "F.Fab")
		)
		(fp_line
			(start -0.2794 -0.1016)
			(end -0.2794 0.9906)
			(stroke
				(width 0.1)
				(type default)
			)
			(layer "F.Fab")
		)
		(fp_line
			(start 0.2794 -0.1016)
			(end -0.2794 -0.1016)
			(stroke
				(width 0.1)
				(type default)
			)
			(layer "F.Fab")
		)
		(pad "1" smd rect
			(at 0 0 270)
			(size 0.508 0.508)
			(layers "F.Cu" "F.Mask" "F.Paste")
			(net "PVPP_ABC")
		)
		(pad "2" smd rect
			(at 0 0.889 270)
			(size 0.508 0.508)
			(layers "F.Cu" "F.Mask" "F.Paste")
			(net "RST_HFI1_CPU0_LVT2_N")
		)
		(zone
			(layer "F.Cu")
			(hatch none 0.5)
			(connect_pads
				(clearance 0)
			)
			(min_thickness 0.25)
			(keepout
				(tracks not_allowed)
				(vias allowed)
				(pads allowed)
				(copperpour not_allowed)
				(footprints allowed)
			)
			(placement
				(enabled no)
				(sheetname "")
			)
			(fill
				(thermal_gap 0.5)
				(thermal_bridge_width 0.5)
				(island_removal_mode 0)
			)
			(polygon
				(pts
					(xy 425.8183 -125.1712) (xy 425.8183 -124.6632) (xy 426.1993 -124.6632) (xy 426.1993 -125.1712)
				)
			)
		)
		(zone
			(layer "F.Cu")
			(hatch none 0.5)
			(connect_pads
				(clearance 0)
			)
			(min_thickness 0.25)
			(keepout
				(tracks allowed)
				(vias not_allowed)
				(pads allowed)
				(copperpour not_allowed)
				(footprints allowed)
			)
			(placement
				(enabled no)
				(sheetname "")
			)
			(fill
				(thermal_gap 0.5)
				(thermal_bridge_width 0.5)
				(island_removal_mode 0)
			)
			(polygon
				(pts
					(xy 426.1993 -125.1712) (xy 426.1993 -124.6632) (xy 425.8183 -124.6632) (xy 425.8183 -125.1712)
				)
			)
		)
	)
	(footprint ""
		(layer "F.Cu")
		(at 271.898872 -73.279)
		(property "Reference" "C5D53"
			(at 0 0 0)
			(layer "F.SilkS")
			(hide yes)
			(effects
				(font
					(size 1.27 1.27)
				)
			)
		)
		(property "Value" ""
			(at 0 0 0)
			(layer "F.Fab")
			(effects
				(font
					(size 1.27 1.27)
				)
			)
		)
		(duplicate_pad_numbers_are_jumpers no)
		(fp_poly
			(pts
				(xy -0.4953 -0.2032) (xy 0.4953 -0.2032) (xy 0.4953 1.6002) (xy -0.4953 1.6002)
			)
			(stroke
				(width 0)
				(type default)
			)
			(fill no)
			(layer "F.CrtYd")
		)
		(fp_line
			(start -0.4953 -0.2032)
			(end 0.4953 -0.2032)
			(stroke
				(width 0.1)
				(type default)
			)
			(layer "F.Fab")
		)
		(fp_line
			(start -0.4953 1.6002)
			(end -0.4953 -0.2032)
			(stroke
				(width 0.1)
				(type default)
			)
			(layer "F.Fab")
		)
		(fp_line
			(start 0.4953 -0.2032)
			(end 0.4953 1.6002)
			(stroke
				(width 0.1)
				(type default)
			)
			(layer "F.Fab")
		)
		(fp_line
			(start 0.4953 1.6002)
			(end -0.4953 1.6002)
			(stroke
				(width 0.1)
				(type default)
			)
			(layer "F.Fab")
		)
		(pad "1" smd rect
			(at 0 0)
			(size 0.762 0.889)
			(layers "F.Cu" "F.Mask" "F.Paste")
			(net "PVCCMCP_CPU0")
		)
		(pad "2" smd rect
			(at 0 1.397)
			(size 0.762 0.889)
			(layers "F.Cu" "F.Mask" "F.Paste")
			(net "GND")
		)
		(zone
			(layer "F.Cu")
			(hatch none 0.5)
			(connect_pads
				(clearance 0)
			)
			(min_thickness 0.25)
			(keepout
				(tracks not_allowed)
				(vias allowed)
				(pads allowed)
				(copperpour not_allowed)
				(footprints allowed)
			)
			(placement
				(enabled no)
				(sheetname "")
			)
			(fill
				(thermal_gap 0.5)
				(thermal_bridge_width 0.5)
				(island_removal_mode 0)
			)
			(polygon
				(pts
					(xy 271.517872 -72.8345) (xy 272.279872 -72.8345) (xy 272.279872 -72.3265) (xy 271.517872 -72.3265)
				)
			)
		)
	)
)
